(kicad_pcb
	(version 20241229)
	(generator "pcbnew")
	(generator_version "9.0")
	(general
		(thickness 1.6296)
		(legacy_teardrops no)
	)
	(paper "A3")
	(title_block
		(title "Thunderbolt to 10GbE adapter")
		(date "2026-04-21")
		(rev "1.1.0")
		(company "Antmicro Ltd")
		(comment 1 "www.antmicro.com")
		(comment 9 "footprints 658-661 of 703")
	)
	(layers
		(0 "F.Cu" signal)
		(4 "In1.Cu" signal)
		(6 "In2.Cu" signal)
		(8 "In3.Cu" signal)
		(10 "In4.Cu" signal)
		(12 "In5.Cu" signal)
		(14 "In6.Cu" signal)
		(2 "B.Cu" signal)
		(9 "F.Adhes" user "F.Adhesive")
		(11 "B.Adhes" user "B.Adhesive")
		(13 "F.Paste" user)
		(15 "B.Paste" user)
		(5 "F.SilkS" user "F.Silkscreen")
		(7 "B.SilkS" user "B.Silkscreen")
		(1 "F.Mask" user)
		(3 "B.Mask" user)
		(17 "Dwgs.User" user "User.Drawings")
		(19 "Cmts.User" user "User.Comments")
		(21 "Eco1.User" user "User.Eco1")
		(23 "Eco2.User" user "User.Eco2")
		(25 "Edge.Cuts" user)
		(27 "Margin" user)
		(31 "F.CrtYd" user "F.Courtyard")
		(29 "B.CrtYd" user "B.Courtyard")
		(35 "F.Fab" user)
		(33 "B.Fab" user)
	)
	(footprint "antmicro-footprints:C_0402_1005Metric"
		(layer "B.Cu")
		(at 130.449999 122.000001 -90)
		(descr "Capacitor SMD 0402")
		(tags "capacitor SMD 0402")
		(property "Reference" "C58"
			(at -7.700002 -21.900002 90)
			(layer "B.SilkS")
			(effects
				(font
					(size 0.7 0.7)
					(thickness 0.15)
				)
				(justify mirror)
			)
		)
		(property "Value" "C_1u_0402"
			(at -1.022927 -2.155213 90)
			(layer "B.Fab")
			(effects
				(font
					(size 0.7 0.7)
					(thickness 0.15)
				)
				(justify left bottom mirror)
			)
		)
		(property "Datasheet" "https://product.tdk.com/en/search/capacitor/ceramic/mlcc/info?part_no=C1005X6S1A105K050BC"
			(at 0 0 90)
			(layer "B.Fab")
			(hide yes)
			(effects
				(font
					(size 1.27 1.27)
					(thickness 0.15)
				)
				(justify mirror)
			)
		)
		(property "Description" "SMD Multilayer Ceramic Capacitor, 1 µF, 10 V, 0402 [1005 Metric], ± 10%, X6S, C"
			(at 0 0 90)
			(layer "B.Fab")
			(hide yes)
			(effects
				(font
					(size 1.27 1.27)
					(thickness 0.15)
				)
				(justify mirror)
			)
		)
		(property "MPN" "C1005X6S1A105K050BC"
			(at 0 0 270)
			(unlocked yes)
			(layer "B.Fab")
			(hide yes)
			(effects
				(font
					(size 1 1)
					(thickness 0.15)
				)
				(justify mirror)
			)
		)
		(property "Manufacturer" "TDK"
			(at 0 0 270)
			(unlocked yes)
			(layer "B.Fab")
			(hide yes)
			(effects
				(font
					(size 1 1)
					(thickness 0.15)
				)
				(justify mirror)
			)
		)
		(property "License" "Apache-2.0"
			(at 0 0 270)
			(unlocked yes)
			(layer "B.Fab")
			(hide yes)
			(effects
				(font
					(size 1 1)
					(thickness 0.15)
				)
				(justify mirror)
			)
		)
		(property "Val" "1u"
			(at 0 0 270)
			(unlocked yes)
			(layer "B.Fab")
			(hide yes)
			(effects
				(font
					(size 1 1)
					(thickness 0.15)
				)
				(justify mirror)
			)
		)
		(property "Voltage" ""
			(at 0 0 270)
			(unlocked yes)
			(layer "B.Fab")
			(hide yes)
			(effects
				(font
					(size 1 1)
					(thickness 0.15)
				)
				(justify mirror)
			)
		)
		(property "Dielectric" ""
			(at 0 0 270)
			(unlocked yes)
			(layer "B.Fab")
			(hide yes)
			(effects
				(font
					(size 1 1)
					(thickness 0.15)
				)
				(justify mirror)
			)
		)
		(property "Author" "Antmicro"
			(at 0 0 270)
			(unlocked yes)
			(layer "B.Fab")
			(hide yes)
			(effects
				(font
					(size 1 1)
					(thickness 0.15)
				)
				(justify mirror)
			)
		)
		(sheetname "/TB Controller - Power/")
		(sheetfile "tb-power.kicad_sch")
		(attr smd)
		(fp_rect
			(start -0.925 0.47)
			(end 0.925 -0.47)
			(stroke
				(width 0.05)
				(type default)
			)
			(fill no)
			(layer "B.CrtYd")
		)
		(fp_line
			(start -0.494 0.25)
			(end 0.504 0.25)
			(stroke
				(width 0.15)
				(type solid)
			)
			(layer "B.Fab")
		)
		(fp_line
			(start 0.504 0.25)
			(end 0.504 -0.248)
			(stroke
				(width 0.15)
				(type solid)
			)
			(layer "B.Fab")
		)
		(fp_line
			(start -0.494 -0.248)
			(end -0.494 0.25)
			(stroke
				(width 0.15)
				(type solid)
			)
			(layer "B.Fab")
		)
		(fp_line
			(start 0.504 -0.248)
			(end -0.494 -0.248)
			(stroke
				(width 0.15)
				(type solid)
			)
			(layer "B.Fab")
		)
		(fp_text user "Author: Antmicro"
			(at -0.939 -3.399 90)
			(layer "B.Fab")
			(effects
				(font
					(size 0.7 0.7)
					(thickness 0.15)
				)
				(justify left bottom mirror)
			)
		)
		(fp_text user "${REFERENCE}"
			(at -0.939 -4.599 90)
			(layer "B.Fab")
			(effects
				(font
					(size 0.7 0.7)
					(thickness 0.15)
				)
				(justify left bottom mirror)
			)
		)
		(fp_text user "License: Apache-2.0"
			(at -0.939 -5.799 90)
			(layer "B.Fab")
			(effects
				(font
					(size 0.7 0.7)
					(thickness 0.15)
				)
				(justify left bottom mirror)
			)
		)
		(pad "1" smd roundrect
			(at -0.48 0 270)
			(size 0.59 0.64)
			(layers "B.Cu" "B.Mask" "B.Paste")
			(roundrect_rratio 0.25)
			(net 23 "GND")
			(pintype "passive")
		)
		(pad "2" smd roundrect
			(at 0.48 0 270)
			(size 0.59 0.64)
			(layers "B.Cu" "B.Mask" "B.Paste")
			(roundrect_rratio 0.25)
			(net 404 "Net-(C58-Pad2)")
			(pintype "passive")
		)
	)
	(footprint "antmicro-footprints:C_0402_1005Metric"
		(layer "B.Cu")
		(at 175.579998 146.66 -90)
		(descr "Capacitor SMD 0402")
		(tags "capacitor SMD 0402")
		(property "Reference" "C303"
			(at 1.09 -0.42 90)
			(layer "B.SilkS")
			(effects
				(font
					(size 0.7 0.7)
					(thickness 0.15)
				)
				(justify left bottom mirror)
			)
		)
		(property "Value" "C_470p_0402"
			(at -1.022927 -2.155213 90)
			(layer "B.Fab")
			(effects
				(font
					(size 0.7 0.7)
					(thickness 0.15)
				)
				(justify left bottom mirror)
			)
		)
		(property "Datasheet" "https://www.passivecomponent.com/wp-content/uploads/datasheet/WTC_MLCC_General_Purpose.pdf"
			(at 0 0 90)
			(layer "B.Fab")
			(hide yes)
			(effects
				(font
					(size 1.27 1.27)
					(thickness 0.15)
				)
				(justify mirror)
			)
		)
		(property "Description" "SMD Multilayer Ceramic Capacitor, General Purpose, 470 pF, 25 V, 0402 [1005 Metric], ± 10%, X7R"
			(at 0 0 90)
			(layer "B.Fab")
			(hide yes)
			(effects
				(font
					(size 1.27 1.27)
					(thickness 0.15)
				)
				(justify mirror)
			)
		)
		(property "MPN" "0402B471K250CT"
			(at 0 0 270)
			(unlocked yes)
			(layer "B.Fab")
			(hide yes)
			(effects
				(font
					(size 1 1)
					(thickness 0.15)
				)
				(justify mirror)
			)
		)
		(property "Manufacturer" "Walsin"
			(at 0 0 270)
			(unlocked yes)
			(layer "B.Fab")
			(hide yes)
			(effects
				(font
					(size 1 1)
					(thickness 0.15)
				)
				(justify mirror)
			)
		)
		(property "License" "Apache-2.0"
			(at 0 0 270)
			(unlocked yes)
			(layer "B.Fab")
			(hide yes)
			(effects
				(font
					(size 1 1)
					(thickness 0.15)
				)
				(justify mirror)
			)
		)
		(property "Author" "Antmicro"
			(at 0 0 270)
			(unlocked yes)
			(layer "B.Fab")
			(hide yes)
			(effects
				(font
					(size 1 1)
					(thickness 0.15)
				)
				(justify mirror)
			)
		)
		(property "Val" "470p"
			(at 0 0 270)
			(unlocked yes)
			(layer "B.Fab")
			(hide yes)
			(effects
				(font
					(size 1 1)
					(thickness 0.15)
				)
				(justify mirror)
			)
		)
		(property "Voltage" "25V"
			(at 0 0 270)
			(unlocked yes)
			(layer "B.Fab")
			(hide yes)
			(effects
				(font
					(size 1 1)
					(thickness 0.15)
				)
				(justify mirror)
			)
		)
		(property "Dielectric" "X7R"
			(at 0 0 270)
			(unlocked yes)
			(layer "B.Fab")
			(hide yes)
			(effects
				(font
					(size 1 1)
					(thickness 0.15)
				)
				(justify mirror)
			)
		)
		(sheetname "/2xRJ45/")
		(sheetfile "2xrj45.kicad_sch")
		(attr smd)
		(fp_rect
			(start -0.925 0.47)
			(end 0.925 -0.47)
			(stroke
				(width 0.05)
				(type default)
			)
			(fill no)
			(layer "B.CrtYd")
		)
		(fp_line
			(start -0.494 0.25)
			(end 0.504 0.25)
			(stroke
				(width 0.15)
				(type solid)
			)
			(layer "B.Fab")
		)
		(fp_line
			(start 0.504 0.25)
			(end 0.504 -0.248)
			(stroke
				(width 0.15)
				(type solid)
			)
			(layer "B.Fab")
		)
		(fp_line
			(start -0.494 -0.248)
			(end -0.494 0.25)
			(stroke
				(width 0.15)
				(type solid)
			)
			(layer "B.Fab")
		)
		(fp_line
			(start 0.504 -0.248)
			(end -0.494 -0.248)
			(stroke
				(width 0.15)
				(type solid)
			)
			(layer "B.Fab")
		)
		(fp_text user "${REFERENCE}"
			(at -0.939 -4.599 90)
			(layer "B.Fab")
			(effects
				(font
					(size 0.7 0.7)
					(thickness 0.15)
				)
				(justify left bottom mirror)
			)
		)
		(fp_text user "Author: Antmicro"
			(at -0.939 -3.399 90)
			(layer "B.Fab")
			(effects
				(font
					(size 0.7 0.7)
					(thickness 0.15)
				)
				(justify left bottom mirror)
			)
		)
		(fp_text user "License: Apache-2.0"
			(at -0.939 -5.799 90)
			(layer "B.Fab")
			(effects
				(font
					(size 0.7 0.7)
					(thickness 0.15)
				)
				(justify left bottom mirror)
			)
		)
		(pad "1" smd roundrect
			(at -0.48 0 270)
			(size 0.59 0.64)
			(layers "B.Cu" "B.Mask" "B.Paste")
			(roundrect_rratio 0.25)
			(net 23 "GND")
			(pintype "passive")
		)
		(pad "2" smd roundrect
			(at 0.48 0 270)
			(size 0.59 0.64)
			(layers "B.Cu" "B.Mask" "B.Paste")
			(roundrect_rratio 0.25)
			(net 407 "Net-(J4-LED_YG_Y-)")
			(pintype "passive")
		)
	)
	(footprint "antmicro-footprints:R_0402_1005Metric"
		(layer "B.Cu")
		(at 146.681866 92.485118 -90)
		(descr "Resistor SMD 0402")
		(tags "resistor SMD 0402")
		(property "Reference" "R177"
			(at 10.814884 -18.718134 90)
			(layer "B.SilkS")
			(effects
				(font
					(size 0.7 0.7)
					(thickness 0.15)
				)
				(justify mirror)
			)
		)
		(property "Value" "R_10k_0402"
			(at -1.011843 -1.772047 90)
			(layer "B.Fab")
			(effects
				(font
					(size 0.7 0.7)
					(thickness 0.15)
				)
				(justify left bottom mirror)
			)
		)
		(property "Datasheet" "https://www.bourns.com/docs/product-datasheets/cr.pdf"
			(at 0 0 90)
			(layer "B.Fab")
			(hide yes)
			(effects
				(font
					(size 1.27 1.27)
					(thickness 0.15)
				)
				(justify mirror)
			)
		)
		(property "Description" "SMD Chip Resistor, 10 kohm, ± 1%, 62.5 mW, 0402 [1005 Metric], Thick Film, General Purpose"
			(at 0 0 90)
			(layer "B.Fab")
			(hide yes)
			(effects
				(font
					(size 1.27 1.27)
					(thickness 0.15)
				)
				(justify mirror)
			)
		)
		(property "MPN" "CR0402-FX-1002GLF"
			(at 0 0 270)
			(unlocked yes)
			(layer "B.Fab")
			(hide yes)
			(effects
				(font
					(size 1 1)
					(thickness 0.15)
				)
				(justify mirror)
			)
		)
		(property "Manufacturer" "Bourns"
			(at 0 0 270)
			(unlocked yes)
			(layer "B.Fab")
			(hide yes)
			(effects
				(font
					(size 1 1)
					(thickness 0.15)
				)
				(justify mirror)
			)
		)
		(property "License" "Apache-2.0"
			(at 0 0 270)
			(unlocked yes)
			(layer "B.Fab")
			(hide yes)
			(effects
				(font
					(size 1 1)
					(thickness 0.15)
				)
				(justify mirror)
			)
		)
		(property "Author" "Antmicro"
			(at 0 0 270)
			(unlocked yes)
			(layer "B.Fab")
			(hide yes)
			(effects
				(font
					(size 1 1)
					(thickness 0.15)
				)
				(justify mirror)
			)
		)
		(property "Val" "10k"
			(at 0 0 270)
			(unlocked yes)
			(layer "B.Fab")
			(hide yes)
			(effects
				(font
					(size 1 1)
					(thickness 0.15)
				)
				(justify mirror)
			)
		)
		(property "Tolerance" "1%"
			(at 0 0 270)
			(unlocked yes)
			(layer "B.Fab")
			(hide yes)
			(effects
				(font
					(size 1 1)
					(thickness 0.15)
				)
				(justify mirror)
			)
		)
		(sheetname "/X710-AT2 Misc/")
		(sheetfile "x710-at2-mics.kicad_sch")
		(attr smd)
		(fp_rect
			(start -0.925 0.47)
			(end 0.925 -0.47)
			(stroke
				(width 0.05)
				(type default)
			)
			(fill no)
			(layer "B.CrtYd")
		)
		(fp_rect
			(start -0.5 0.25)
			(end 0.5 -0.25)
			(stroke
				(width 0.15)
				(type solid)
			)
			(fill no)
			(layer "B.Fab")
		)
		(fp_text user "Author: Antmicro"
			(at -0.95 -4.169 90)
			(layer "B.Fab")
			(effects
				(font
					(size 0.7 0.7)
					(thickness 0.15)
				)
				(justify left bottom mirror)
			)
		)
		(fp_text user "License: Apache-2.0"
			(at -0.95 -5.169 90)
			(layer "B.Fab")
			(effects
				(font
					(size 0.7 0.7)
					(thickness 0.15)
				)
				(justify left bottom mirror)
			)
		)
		(fp_text user "${REFERENCE}"
			(at -0.95 -3.168 90)
			(layer "B.Fab")
			(effects
				(font
					(size 0.7 0.7)
					(thickness 0.15)
				)
				(justify left bottom mirror)
			)
		)
		(pad "1" smd roundrect
			(at -0.48 0 270)
			(size 0.59 0.64)
			(layers "B.Cu" "B.Mask" "B.Paste")
			(roundrect_rratio 0.25)
			(net 73 "/X710-AT2 Misc/~{SMBALRT}")
			(pintype "passive")
		)
		(pad "2" smd roundrect
			(at 0.48 0 270)
			(size 0.59 0.64)
			(layers "B.Cu" "B.Mask" "B.Paste")
			(roundrect_rratio 0.25)
			(net 7 "+3V3")
			(pintype "passive")
		)
	)
	(footprint "antmicro-footprints:C_0805_2012Metric"
		(layer "B.Cu")
		(at 166.6 139.25)
		(descr "Capacitor SMD 0805")
		(tags "capacitor SMD 0805")
		(property "Reference" "C293"
			(at 4.9 0.5 180)
			(layer "B.SilkS")
			(effects
				(font
					(size 0.7 0.7)
					(thickness 0.15)
				)
				(justify left bottom mirror)
			)
		)
		(property "Value" "C_100u_0805"
			(at -2.055717 -1.963152 180)
			(layer "B.Fab")
			(effects
				(font
					(size 0.7 0.7)
					(thickness 0.15)
				)
				(justify left bottom mirror)
			)
		)
		(property "Datasheet" "https://www.murata.com/products/productdetail?partno=GRM21BR60J107ME15%23"
			(at 0 0 180)
			(layer "B.Fab")
			(hide yes)
			(effects
				(font
					(size 1.27 1.27)
					(thickness 0.15)
				)
				(justify mirror)
			)
		)
		(property "Description" "SMD Multilayer Ceramic Capacitor, 100 µF, 6.3 V, 0805 [2012 Metric], ± 20%, X5R, GRM Series"
			(at 0 0 180)
			(layer "B.Fab")
			(hide yes)
			(effects
				(font
					(size 1.27 1.27)
					(thickness 0.15)
				)
				(justify mirror)
			)
		)
		(property "MPN" "GRM21BR60J107ME15L"
			(at 0 0 0)
			(unlocked yes)
			(layer "B.Fab")
			(hide yes)
			(effects
				(font
					(size 1 1)
					(thickness 0.15)
				)
				(justify mirror)
			)
		)
		(property "Manufacturer" "Murata"
			(at 0 0 0)
			(unlocked yes)
			(layer "B.Fab")
			(hide yes)
			(effects
				(font
					(size 1 1)
					(thickness 0.15)
				)
				(justify mirror)
			)
		)
		(property "License" "Apache-2.0"
			(at 0 0 0)
			(unlocked yes)
			(layer "B.Fab")
			(hide yes)
			(effects
				(font
					(size 1 1)
					(thickness 0.15)
				)
				(justify mirror)
			)
		)
		(property "Author" "Antmicro"
			(at 0 0 0)
			(unlocked yes)
			(layer "B.Fab")
			(hide yes)
			(effects
				(font
					(size 1 1)
					(thickness 0.15)
				)
				(justify mirror)
			)
		)
		(property "Val" "100u"
			(at 0 0 0)
			(unlocked yes)
			(layer "B.Fab")
			(hide yes)
			(effects
				(font
					(size 1 1)
					(thickness 0.15)
				)
				(justify mirror)
			)
		)
		(property "Voltage" ""
			(at 0 0 0)
			(unlocked yes)
			(layer "B.Fab")
			(hide yes)
			(effects
				(font
					(size 1 1)
					(thickness 0.15)
				)
				(justify mirror)
			)
		)
		(property "Dielectric" ""
			(at 0 0 0)
			(unlocked yes)
			(layer "B.Fab")
			(hide yes)
			(effects
				(font
					(size 1 1)
					(thickness 0.15)
				)
				(justify mirror)
			)
		)
		(property "Public" "False"
			(at 0 0 0)
			(unlocked yes)
			(layer "B.Fab")
			(hide yes)
			(effects
				(font
					(size 1 1)
					(thickness 0.15)
				)
				(justify mirror)
			)
		)
		(sheetname "/2xRJ45/")
		(sheetfile "2xrj45.kicad_sch")
		(attr smd)
		(fp_line
			(start -0.3 -0.7)
			(end 0.3 -0.7)
			(stroke
				(width 0.15)
				(type solid)
			)
			(layer "B.SilkS")
		)
		(fp_line
			(start -0.3 0.7)
			(end 0.3 0.7)
			(stroke
				(width 0.15)
				(type solid)
			)
			(layer "B.SilkS")
		)
		(fp_rect
			(start 1.95 0.9)
			(end -1.95 -0.9)
			(stroke
				(width 0.05)
				(type default)
			)
			(fill no)
			(layer "B.CrtYd")
		)
		(fp_rect
			(start -0.95 0.675)
			(end 0.95 -0.675)
			(stroke
				(width 0.15)
				(type solid)
			)
			(fill no)
			(layer "B.Fab")
		)
		(fp_text user "Author: Antmicro"
			(at -1.9 -5.947 180)
			(layer "B.Fab")
			(effects
				(font
					(size 0.7 0.7)
					(thickness 0.15)
				)
				(justify left bottom mirror)
			)
		)
		(fp_text user "${REFERENCE}"
			(at -1.9 -3.947 180)
			(layer "B.Fab")
			(effects
				(font
					(size 0.7 0.7)
					(thickness 0.15)
				)
				(justify left bottom mirror)
			)
		)
		(fp_text user "License: Apache-2.0"
			(at -1.9 -4.947 180)
			(layer "B.Fab")
			(effects
				(font
					(size 0.7 0.7)
					(thickness 0.15)
				)
				(justify left bottom mirror)
			)
		)
		(pad "1" smd roundrect
			(at -1.1 0)
			(size 1.2 1.3)
			(layers "B.Cu" "B.Mask" "B.Paste")
			(roundrect_rratio 0.25)
			(net 23 "GND")
			(pintype "passive")
		)
		(pad "2" smd roundrect
			(at 1.1 0)
			(size 1.2 1.3)
			(layers "B.Cu" "B.Mask" "B.Paste")
			(roundrect_rratio 0.25)
			(net 134 "/2xRJ45/P1_CT")
			(pintype "passive")
		)
	)
)
